# T6G (Grand Teton) — schematic netlist excerpt (pin names and nets, part order shuffled) for the footprints in the layout excerpt that follows; sources: Cadence DE-HDL packaged netlist, KiCad conversion of 04192023_DAF0TMB3IC0_F0TG_MB_C_brd_V02_OCP.brd

PC6556_1  Q_CAP  22UF 16V 20% X6S  pkg C0805  page 363 : A = SW_P12V_AUX_P0V9_RETIMER_CPU0_FLT ; B = GND
C8002  Q_CAP  0.1UF 25V 10% EMPTY  pkg 0402  page 143 : A = OCP_SFF_PRSNT23_R1_N ; B = GND
R566  Q_RES  0 5% CHIP  pkg 0402LF  page 159 : A = I3C_1_SPD_DDRGL_CPU1_SCL ; B = I3C_1_SPD_DDRGL_CPU1_R_SCL

(kicad_pcb
	(version 20260206)
	(generator "pcbnew")
	(generator_version "10.0")
	(general
		(thickness 1.6)
		(legacy_teardrops no)
	)
	(paper "A4")
	(title_block
		(title "04192023_DAF0TMB3IC0_F0TG_MB_C_brd_V02_OCP.brd")
		(comment 1 "Grand Teton / footprints 6209-6211 of 8354")
	)
	(layers
		(0 "F.Cu" signal "TOP")
		(4 "In1.Cu" signal "GND")
		(6 "In2.Cu" signal "IN1")
		(8 "In3.Cu" signal "GND1")
		(10 "In4.Cu" signal "IN2")
		(12 "In5.Cu" signal "GND2")
		(14 "In6.Cu" signal "IN3")
		(16 "In7.Cu" signal "GND3")
		(18 "In8.Cu" signal "VCC")
		(20 "In9.Cu" signal "VCC1")
		(22 "In10.Cu" signal "GND4")
		(24 "In11.Cu" signal "IN4")
		(26 "In12.Cu" signal "GND5")
		(28 "In13.Cu" signal "IN5")
		(30 "In14.Cu" signal "GND6")
		(32 "In15.Cu" signal "IN6")
		(34 "In16.Cu" signal "GND7")
		(2 "B.Cu" signal "BOTTOM")
		(9 "F.Adhes" user "F.Adhesive")
		(11 "B.Adhes" user "B.Adhesive")
		(13 "F.Paste" user "Package Geometry/Pastemask Top")
		(15 "B.Paste" user "Package Geometry/Pastemask Bottom")
		(5 "F.SilkS" user "Ref Des/Silkscreen Top")
		(7 "B.SilkS" user "Ref Des/Silkscreen Bottom")
		(1 "F.Mask" user "Board Geometry/Soldermask Top")
		(3 "B.Mask" user "Board Geometry/Soldermask Bottom")
		(17 "Dwgs.User" user "User.Drawings")
		(19 "Cmts.User" user "User.Comments")
		(21 "Eco1.User" user "User.Eco1")
		(23 "Eco2.User" user "User.Eco2")
		(25 "Edge.Cuts" user "Board Geometry/Outline")
		(27 "Margin" user)
		(31 "F.CrtYd" user "Package Geometry/Place Bound Top")
		(29 "B.CrtYd" user "Package Geometry/Place Bound Bottom")
		(35 "F.Fab" user "Ref Des/Assembly Top")
		(33 "B.Fab" user "Ref Des/Assembly Bottom")
	)
	(footprint ""
		(layer "B.Cu")
		(at 9.271 -81.153 -90)
		(property "Reference" "C8002"
			(at 0 0 90)
			(layer "B.SilkS")
			(hide yes)
			(effects
				(font
					(size 1.27 1.27)
				)
				(justify mirror)
			)
		)
		(property "Value" ""
			(at 0 0 90)
			(layer "B.Fab")
			(effects
				(font
					(size 1.27 1.27)
				)
				(justify mirror)
			)
		)
		(duplicate_pad_numbers_are_jumpers no)
		(fp_line
			(start -0.7874 0.4064)
			(end 0.7874 0.4064)
			(stroke
				(width 0.1524)
				(type default)
			)
			(layer "B.SilkS")
		)
		(fp_line
			(start 0.7874 0.4064)
			(end 0.7874 -0.4064)
			(stroke
				(width 0.1524)
				(type default)
			)
			(layer "B.SilkS")
		)
		(fp_line
			(start -0.7874 -0.4064)
			(end -0.7874 0.4064)
			(stroke
				(width 0.1524)
				(type default)
			)
			(layer "B.SilkS")
		)
		(fp_line
			(start 0.7874 -0.4064)
			(end -0.7874 -0.4064)
			(stroke
				(width 0.1524)
				(type default)
			)
			(layer "B.SilkS")
		)
		(fp_line
			(start -0.67945 0.3048)
			(end -0.120396 0.3048)
			(stroke
				(width 0.1)
				(type default)
			)
			(layer "B.Fab")
		)
		(fp_line
			(start -0.120396 0.3048)
			(end -0.120396 0.2794)
			(stroke
				(width 0.1)
				(type default)
			)
			(layer "B.Fab")
		)
		(fp_line
			(start 0.12065 0.3048)
			(end 0.67945 0.3048)
			(stroke
				(width 0.1)
				(type default)
			)
			(layer "B.Fab")
		)
		(fp_line
			(start 0.67945 0.3048)
			(end 0.67945 -0.305054)
			(stroke
				(width 0.1)
				(type default)
			)
			(layer "B.Fab")
		)
		(fp_line
			(start -0.120396 0.2794)
			(end 0.12065 0.2794)
			(stroke
				(width 0.1)
				(type default)
			)
			(layer "B.Fab")
		)
		(fp_line
			(start 0.12065 0.2794)
			(end 0.12065 0.3048)
			(stroke
				(width 0.1)
				(type default)
			)
			(layer "B.Fab")
		)
		(fp_line
			(start -0.12065 -0.2794)
			(end -0.12065 -0.3048)
			(stroke
				(width 0.1)
				(type default)
			)
			(layer "B.Fab")
		)
		(fp_line
			(start 0.12065 -0.2794)
			(end -0.12065 -0.2794)
			(stroke
				(width 0.1)
				(type default)
			)
			(layer "B.Fab")
		)
		(fp_line
			(start -0.67945 -0.3048)
			(end -0.67945 0.3048)
			(stroke
				(width 0.1)
				(type default)
			)
			(layer "B.Fab")
		)
		(fp_line
			(start -0.12065 -0.3048)
			(end -0.67945 -0.3048)
			(stroke
				(width 0.1)
				(type default)
			)
			(layer "B.Fab")
		)
		(fp_line
			(start 0.12065 -0.305054)
			(end 0.12065 -0.2794)
			(stroke
				(width 0.1)
				(type default)
			)
			(layer "B.Fab")
		)
		(fp_line
			(start 0.67945 -0.305054)
			(end 0.12065 -0.305054)
			(stroke
				(width 0.1)
				(type default)
			)
			(layer "B.Fab")
		)
		(pad "1" smd circle
			(at 0.40005 0 90)
			(size 0 0)
			(layers "B.Cu" "B.Mask" "B.Paste")
			(net "OCP_SFF_PRSNT23_R1_N")
		)
		(pad "2" smd circle
			(at -0.40005 0 90)
			(size 0 0)
			(layers "B.Cu" "B.Mask" "B.Paste")
			(net "GND")
		)
	)
	(footprint ""
		(layer "B.Cu")
		(at 446.253616 -397.05407 90)
		(property "Reference" "PC6556_1"
			(at 0 0 90)
			(layer "B.SilkS")
			(hide yes)
			(effects
				(font
					(size 1.27 1.27)
				)
				(justify mirror)
			)
		)
		(property "Value" ""
			(at 0 0 90)
			(layer "B.Fab")
			(effects
				(font
					(size 1.27 1.27)
				)
				(justify mirror)
			)
		)
		(duplicate_pad_numbers_are_jumpers no)
		(fp_line
			(start 1.524 -0.762)
			(end -1.524 -0.762)
			(stroke
				(width 0.1524)
				(type default)
			)
			(layer "B.SilkS")
		)
		(fp_line
			(start -1.524 -0.762)
			(end -1.524 0.762)
			(stroke
				(width 0.1524)
				(type default)
			)
			(layer "B.SilkS")
		)
		(fp_line
			(start 1.524 0.762)
			(end 1.524 -0.762)
			(stroke
				(width 0.1524)
				(type default)
			)
			(layer "B.SilkS")
		)
		(fp_line
			(start -1.524 0.762)
			(end 1.524 0.762)
			(stroke
				(width 0.1524)
				(type default)
			)
			(layer "B.SilkS")
		)
		(fp_line
			(start 1.1049 -0.724916)
			(end 1.1049 0.724916)
			(stroke
				(width 0.1)
				(type default)
			)
			(layer "B.Fab")
		)
		(fp_line
			(start -1.1049 -0.724916)
			(end 1.1049 -0.724916)
			(stroke
				(width 0.1)
				(type default)
			)
			(layer "B.Fab")
		)
		(fp_line
			(start 1.1049 0.724916)
			(end -1.1049 0.724916)
			(stroke
				(width 0.1)
				(type default)
			)
			(layer "B.Fab")
		)
		(fp_line
			(start -1.1049 0.724916)
			(end -1.1049 -0.724916)
			(stroke
				(width 0.1)
				(type default)
			)
			(layer "B.Fab")
		)
		(pad "1" smd rect
			(at 0.889 0 90)
			(size 1.016 1.27)
			(layers "B.Cu" "B.Mask" "B.Paste")
			(net "SW_P12V_AUX_P0V9_RETIMER_CPU0_FLT")
		)
		(pad "2" smd rect
			(at -0.889 0 90)
			(size 1.016 1.27)
			(layers "B.Cu" "B.Mask" "B.Paste")
			(net "GND")
		)
	)
	(footprint ""
		(layer "B.Cu")
		(at 159.615632 -193.148966 -90)
		(property "Reference" "R566"
			(at 0 0 90)
			(layer "B.SilkS")
			(hide yes)
			(effects
				(font
					(size 1.27 1.27)
				)
				(justify mirror)
			)
		)
		(property "Value" ""
			(at 0 0 90)
			(layer "B.Fab")
			(effects
				(font
					(size 1.27 1.27)
				)
				(justify mirror)
			)
		)
		(duplicate_pad_numbers_are_jumpers no)
		(fp_line
			(start -0.7874 0.4064)
			(end 0.7874 0.4064)
			(stroke
				(width 0.1524)
				(type default)
			)
			(layer "B.SilkS")
		)
		(fp_line
			(start 0.7874 0.4064)
			(end 0.7874 -0.4064)
			(stroke
				(width 0.1524)
				(type default)
			)
			(layer "B.SilkS")
		)
		(fp_line
			(start -0.7874 -0.4064)
			(end -0.7874 0.4064)
			(stroke
				(width 0.1524)
				(type default)
			)
			(layer "B.SilkS")
		)
		(fp_line
			(start 0.7874 -0.4064)
			(end -0.7874 -0.4064)
			(stroke
				(width 0.1524)
				(type default)
			)
			(layer "B.SilkS")
		)
		(fp_line
			(start -0.67945 0.3048)
			(end -0.120396 0.3048)
			(stroke
				(width 0.1)
				(type default)
			)
			(layer "B.Fab")
		)
		(fp_line
			(start -0.120396 0.3048)
			(end -0.120396 0.2794)
			(stroke
				(width 0.1)
				(type default)
			)
			(layer "B.Fab")
		)
		(fp_line
			(start 0.12065 0.3048)
			(end 0.67945 0.3048)
			(stroke
				(width 0.1)
				(type default)
			)
			(layer "B.Fab")
		)
		(fp_line
			(start 0.67945 0.3048)
			(end 0.67945 -0.305054)
			(stroke
				(width 0.1)
				(type default)
			)
			(layer "B.Fab")
		)
		(fp_line
			(start -0.120396 0.2794)
			(end 0.12065 0.2794)
			(stroke
				(width 0.1)
				(type default)
			)
			(layer "B.Fab")
		)
		(fp_line
			(start 0.12065 0.2794)
			(end 0.12065 0.3048)
			(stroke
				(width 0.1)
				(type default)
			)
			(layer "B.Fab")
		)
		(fp_line
			(start -0.12065 -0.2794)
			(end -0.12065 -0.3048)
			(stroke
				(width 0.1)
				(type default)
			)
			(layer "B.Fab")
		)
		(fp_line
			(start 0.12065 -0.2794)
			(end -0.12065 -0.2794)
			(stroke
				(width 0.1)
				(type default)
			)
			(layer "B.Fab")
		)
		(fp_line
			(start -0.67945 -0.3048)
			(end -0.67945 0.3048)
			(stroke
				(width 0.1)
				(type default)
			)
			(layer "B.Fab")
		)
		(fp_line
			(start -0.12065 -0.3048)
			(end -0.67945 -0.3048)
			(stroke
				(width 0.1)
				(type default)
			)
			(layer "B.Fab")
		)
		(fp_line
			(start 0.12065 -0.305054)
			(end 0.12065 -0.2794)
			(stroke
				(width 0.1)
				(type default)
			)
			(layer "B.Fab")
		)
		(fp_line
			(start 0.67945 -0.305054)
			(end 0.12065 -0.305054)
			(stroke
				(width 0.1)
				(type default)
			)
			(layer "B.Fab")
		)
		(pad "1" smd rect
			(at 0.40005 0 270)
			(size 0.4572 0.508)
			(layers "B.Cu" "B.Mask" "B.Paste")
			(net "I3C_1_SPD_DDRGL_CPU1_SCL")
		)
		(pad "2" smd rect
			(at -0.40005 0 270)
			(size 0.4572 0.508)
			(layers "B.Cu" "B.Mask" "B.Paste")
			(net "I3C_1_SPD_DDRGL_CPU1_R_SCL")
		)
	)
)
